(kicad_pcb
	(version 20260206)
	(generator "pcbnew")
	(generator_version "10.0")
	(general
		(thickness 1.6)
		(legacy_teardrops no)
	)
	(paper "A4")
	(title_block
		(title "01162023_DA0F0TEBIF0_F0T_Expander_BD_F_brd_V02_OCP.brd")
		(comment 1 "Grand Teton / footprints 4456-4456 of 9728")
	)
	(layers
		(0 "F.Cu" signal "TOP")
		(4 "In1.Cu" signal "GND")
		(6 "In2.Cu" signal "VCC")
		(8 "In3.Cu" signal "VCC1")
		(10 "In4.Cu" signal "GND1")
		(12 "In5.Cu" signal "IN1")
		(14 "In6.Cu" signal "GND2")
		(16 "In7.Cu" signal "IN2")
		(18 "In8.Cu" signal "GND3")
		(20 "In9.Cu" signal "IN3")
		(22 "In10.Cu" signal "GND4")
		(24 "In11.Cu" signal "IN4")
		(26 "In12.Cu" signal "GND5")
		(28 "In13.Cu" signal "IN5")
		(30 "In14.Cu" signal "GND6")
		(32 "In15.Cu" signal "IN6")
		(34 "In16.Cu" signal "GND7")
		(2 "B.Cu" signal "BOTTOM")
		(9 "F.Adhes" user "F.Adhesive")
		(11 "B.Adhes" user "B.Adhesive")
		(13 "F.Paste" user "Package Geometry/Pastemask Top")
		(15 "B.Paste" user "Package Geometry/Pastemask Bottom")
		(5 "F.SilkS" user "Ref Des/Silkscreen Top")
		(7 "B.SilkS" user "Ref Des/Silkscreen Bottom")
		(1 "F.Mask" user "Board Geometry/Soldermask Top")
		(3 "B.Mask" user "Board Geometry/Soldermask Bottom")
		(17 "Dwgs.User" user "User.Drawings")
		(19 "Cmts.User" user "User.Comments")
		(21 "Eco1.User" user "User.Eco1")
		(23 "Eco2.User" user "User.Eco2")
		(25 "Edge.Cuts" user "Board Geometry/Outline")
		(27 "Margin" user)
		(31 "F.CrtYd" user "Package Geometry/Place Bound Top")
		(29 "B.CrtYd" user "Package Geometry/Place Bound Bottom")
		(35 "F.Fab" user "Ref Des/Assembly Top")
		(33 "B.Fab" user "Ref Des/Assembly Bottom")
	)
	(footprint ""
		(layer "F.Cu")
		(at 181.064916 -26.785062 180)
		(property "Reference" "J36"
			(at 4.509516 -11.475466 90)
			(unlocked yes)
			(layer "F.SilkS")
			(effects
				(font
					(size 0.7874 0.5842)
					(thickness 0.1524)
				)
			)
		)
		(property "Value" ""
			(at 0 0 180)
			(layer "F.Fab")
			(effects
				(font
					(size 1.27 1.27)
				)
			)
		)
		(duplicate_pad_numbers_are_jumpers no)
		(fp_line
			(start 3.150108 12.115038)
			(end 1.529334 12.115038)
			(stroke
				(width 0.1524)
				(type default)
			)
			(layer "F.SilkS")
		)
		(fp_line
			(start 3.074924 12.014962)
			(end 1.632204 12.014962)
			(stroke
				(width 0.1524)
				(type default)
			)
			(layer "F.SilkS")
		)
		(fp_line
			(start 1.632204 -12.014962)
			(end 3.074924 -12.014962)
			(stroke
				(width 0.1524)
				(type default)
			)
			(layer "F.SilkS")
		)
		(fp_line
			(start 1.529334 -12.115038)
			(end 3.150108 -12.115038)
			(stroke
				(width 0.1524)
				(type default)
			)
			(layer "F.SilkS")
		)
		(fp_line
			(start -1.529334 12.115038)
			(end -3.150108 12.115038)
			(stroke
				(width 0.1524)
				(type default)
			)
			(layer "F.SilkS")
		)
		(fp_line
			(start -1.632204 12.014962)
			(end -3.074924 12.014962)
			(stroke
				(width 0.1524)
				(type default)
			)
			(layer "F.SilkS")
		)
		(fp_line
			(start -3.074924 -12.014962)
			(end -1.632204 -12.014962)
			(stroke
				(width 0.1524)
				(type default)
			)
			(layer "F.SilkS")
		)
		(fp_line
			(start -3.150108 -12.115038)
			(end -1.529334 -12.115038)
			(stroke
				(width 0.1524)
				(type default)
			)
			(layer "F.SilkS")
		)
		(fp_poly
			(pts
				(xy 3.451098 -8.920226) (xy 3.8735 -10.18794) (xy 4.718558 -9.342882)
			)
			(stroke
				(width 0)
				(type default)
			)
			(fill yes)
			(layer "F.SilkS")
		)
		(fp_line
			(start 3.074924 12.014962)
			(end -3.074924 12.014962)
			(stroke
				(width 0.1)
				(type default)
			)
			(layer "F.Fab")
		)
		(fp_line
			(start 3.074924 -12.014962)
			(end 3.074924 12.014962)
			(stroke
				(width 0.1)
				(type default)
			)
			(layer "F.Fab")
		)
		(fp_line
			(start -3.074924 12.014962)
			(end -3.074924 -12.014962)
			(stroke
				(width 0.1)
				(type default)
			)
			(layer "F.Fab")
		)
		(fp_line
			(start -3.074924 -12.014962)
			(end 3.074924 -12.014962)
			(stroke
				(width 0.1)
				(type default)
			)
			(layer "F.Fab")
		)
		(fp_poly
			(pts
				(xy 3.348736 -7.994904) (xy 4.543806 -8.592566) (xy 4.543806 -7.397496)
			)
			(stroke
				(width 0)
				(type default)
			)
			(fill yes)
			(layer "F.Fab")
		)
		(pad "" np_thru_hole circle
			(at -1.75006 -9.815068 90)
			(size 1.1176 1.1176)
			(drill 1.1176)
			(layers "*.Cu" "*.Mask")
			(clearance 0.381)
			(thermal_gap 0.381)
		)
		(pad "" np_thru_hole circle
			(at 0 9.815068 90)
			(size 1.1176 1.1176)
			(drill 1.1176)
			(layers "*.Cu" "*.Mask")
			(clearance 0.381)
			(thermal_gap 0.381)
		)
		(pad "A1" smd rect
			(at 2.29997 -7.994904 90)
			(size 0.381 1.27)
			(layers "F.Cu" "F.Mask" "F.Paste")
			(net "GND")
		)
		(pad "A2" smd rect
			(at 2.29997 -7.394956 90)
			(size 0.381 1.27)
			(layers "F.Cu" "F.Mask" "F.Paste")
			(net "GND")
		)
		(pad "A3" smd rect
			(at 2.29997 -6.795008 90)
			(size 0.381 1.27)
			(layers "F.Cu" "F.Mask" "F.Paste")
			(net "GND")
		)
		(pad "A4" smd rect
			(at 2.29997 -6.19506 90)
			(size 0.381 1.27)
			(layers "F.Cu" "F.Mask" "F.Paste")
			(net "GND")
		)
		(pad "A5" smd rect
			(at 2.29997 -5.595112 90)
			(size 0.381 1.27)
			(layers "F.Cu" "F.Mask" "F.Paste")
			(net "GND")
		)
		(pad "A6" smd rect
			(at 2.29997 -4.99491 90)
			(size 0.381 1.27)
			(layers "F.Cu" "F.Mask" "F.Paste")
			(net "GND")
		)
		(pad "A7" smd rect
			(at 2.29997 -4.394962 90)
			(size 0.381 1.27)
			(layers "F.Cu" "F.Mask" "F.Paste")
			(net "SMB_ISO_SSD6_R_SCL")
		)
		(pad "A8" smd rect
			(at 2.29997 -3.795014 90)
			(size 0.381 1.27)
			(layers "F.Cu" "F.Mask" "F.Paste")
			(net "SMB_ISO_SSD6_R_SDA")
		)
		(pad "A9" smd rect
			(at 2.29997 -3.195066 90)
			(size 0.381 1.27)
			(layers "F.Cu" "F.Mask" "F.Paste")
			(net "RST_SMB_SSD6_ISO_R_N")
		)
		(pad "A10" smd rect
			(at 2.29997 -2.595118 90)
			(size 0.381 1.27)
			(layers "F.Cu" "F.Mask" "F.Paste")
			(net "SSD6_LED_ISO_R_N")
		)
		(pad "A11" smd rect
			(at 2.29997 -1.994916 90)
			(size 0.381 1.27)
			(layers "F.Cu" "F.Mask" "F.Paste")
			(net "PU_CLKREQ6")
		)
		(pad "A12" smd rect
			(at 2.29997 -1.394968 90)
			(size 0.381 1.27)
			(layers "F.Cu" "F.Mask" "F.Paste")
			(net "PRSNT_SSD6_N")
		)
		(pad "A13" smd rect
			(at 2.29997 -0.79502 90)
			(size 0.381 1.27)
			(layers "F.Cu" "F.Mask" "F.Paste")
			(net "GND")
		)
		(pad "A14" smd rect
			(at 2.29997 -0.195072 90)
			(size 0.381 1.27)
			(layers "F.Cu" "F.Mask" "F.Paste")
			(net "Net_8513")
		)
		(pad "A15" smd rect
			(at 2.29997 0.404876 90)
			(size 0.381 1.27)
			(layers "F.Cu" "F.Mask" "F.Paste")
			(net "Net_8512")
		)
		(pad "A16" smd rect
			(at 2.29997 1.005078 90)
			(size 0.381 1.27)
			(layers "F.Cu" "F.Mask" "F.Paste")
			(net "GND")
		)
		(pad "A17" smd rect
			(at 2.29997 1.605026 90)
			(size 0.381 1.27)
			(layers "F.Cu" "F.Mask" "F.Paste")
			(net "P5E_PEX1_STN2_RX_DN<36>")
		)
		(pad "A18" smd rect
			(at 2.29997 2.204974 90)
			(size 0.381 1.27)
			(layers "F.Cu" "F.Mask" "F.Paste")
			(net "P5E_PEX1_STN2_RX_DP<36>")
		)
		(pad "A19" smd rect
			(at 2.29997 2.804922 90)
			(size 0.381 1.27)
			(layers "F.Cu" "F.Mask" "F.Paste")
			(net "GND")
		)
		(pad "A20" smd rect
			(at 2.29997 3.405124 90)
			(size 0.381 1.27)
			(layers "F.Cu" "F.Mask" "F.Paste")
			(net "P5E_PEX1_STN2_RX_DN<37>")
		)
		(pad "A21" smd rect
			(at 2.29997 4.005072 90)
			(size 0.381 1.27)
			(layers "F.Cu" "F.Mask" "F.Paste")
			(net "P5E_PEX1_STN2_RX_DP<37>")
		)
		(pad "A22" smd rect
			(at 2.29997 4.60502 90)
			(size 0.381 1.27)
			(layers "F.Cu" "F.Mask" "F.Paste")
			(net "GND")
		)
		(pad "A23" smd rect
			(at 2.29997 5.204968 90)
			(size 0.381 1.27)
			(layers "F.Cu" "F.Mask" "F.Paste")
			(net "P5E_PEX1_STN2_RX_DN<38>")
		)
		(pad "A24" smd rect
			(at 2.29997 5.804916 90)
			(size 0.381 1.27)
			(layers "F.Cu" "F.Mask" "F.Paste")
			(net "P5E_PEX1_STN2_RX_DP<38>")
		)
		(pad "A25" smd rect
			(at 2.29997 6.405118 90)
			(size 0.381 1.27)
			(layers "F.Cu" "F.Mask" "F.Paste")
			(net "GND")
		)
		(pad "A26" smd rect
			(at 2.29997 7.005066 90)
			(size 0.381 1.27)
			(layers "F.Cu" "F.Mask" "F.Paste")
			(net "P5E_PEX1_STN2_RX_DN<39>")
		)
		(pad "A27" smd rect
			(at 2.29997 7.605014 90)
			(size 0.381 1.27)
			(layers "F.Cu" "F.Mask" "F.Paste")
			(net "P5E_PEX1_STN2_RX_DP<39>")
		)
		(pad "A28" smd rect
			(at 2.29997 8.204962 90)
			(size 0.381 1.27)
			(layers "F.Cu" "F.Mask" "F.Paste")
			(net "GND")
		)
		(pad "B1" smd rect
			(at -2.29997 -7.994904 90)
			(size 0.381 1.27)
			(layers "F.Cu" "F.Mask" "F.Paste")
			(net "P12V_SSD6")
		)
		(pad "B2" smd rect
			(at -2.29997 -7.394956 90)
			(size 0.381 1.27)
			(layers "F.Cu" "F.Mask" "F.Paste")
			(net "P12V_SSD6")
		)
		(pad "B3" smd rect
			(at -2.29997 -6.795008 90)
			(size 0.381 1.27)
			(layers "F.Cu" "F.Mask" "F.Paste")
			(net "P12V_SSD6")
		)
		(pad "B4" smd rect
			(at -2.29997 -6.19506 90)
			(size 0.381 1.27)
			(layers "F.Cu" "F.Mask" "F.Paste")
			(net "P12V_SSD6")
		)
		(pad "B5" smd rect
			(at -2.29997 -5.595112 90)
			(size 0.381 1.27)
			(layers "F.Cu" "F.Mask" "F.Paste")
			(net "P12V_SSD6")
		)
		(pad "B6" smd rect
			(at -2.29997 -4.99491 90)
			(size 0.381 1.27)
			(layers "F.Cu" "F.Mask" "F.Paste")
			(net "P12V_SSD6")
		)
		(pad "B7" smd rect
			(at -2.29997 -4.394962 90)
			(size 0.381 1.27)
			(layers "F.Cu" "F.Mask" "F.Paste")
			(net "Net_8514")
		)
		(pad "B8" smd rect
			(at -2.29997 -3.795014 90)
			(size 0.381 1.27)
			(layers "F.Cu" "F.Mask" "F.Paste")
			(net "Net_8511")
		)
		(pad "B9" smd rect
			(at -2.29997 -3.195066 90)
			(size 0.381 1.27)
			(layers "F.Cu" "F.Mask" "F.Paste")
			(net "DUALPORT_N_SSD6")
		)
		(pad "B10" smd rect
			(at -2.29997 -2.595118 90)
			(size 0.381 1.27)
			(layers "F.Cu" "F.Mask" "F.Paste")
			(net "RST_SSD6_PERST_R_N")
		)
		(pad "B11" smd rect
			(at -2.29997 -1.994916 90)
			(size 0.381 1.27)
			(layers "F.Cu" "F.Mask" "F.Paste")
			(net "P3V3_SSD6")
		)
		(pad "B12" smd rect
			(at -2.29997 -1.394968 90)
			(size 0.381 1.27)
			(layers "F.Cu" "F.Mask" "F.Paste")
			(net "SSD6_PWRDIS_R")
		)
		(pad "B13" smd rect
			(at -2.29997 -0.79502 90)
			(size 0.381 1.27)
			(layers "F.Cu" "F.Mask" "F.Paste")
			(net "GND")
		)
		(pad "B14" smd rect
			(at -2.29997 -0.195072 90)
			(size 0.381 1.27)
			(layers "F.Cu" "F.Mask" "F.Paste")
			(net "CLK_100M_DB800ZL_SSD6_R_DN")
		)
		(pad "B15" smd rect
			(at -2.29997 0.404876 90)
			(size 0.381 1.27)
			(layers "F.Cu" "F.Mask" "F.Paste")
			(net "CLK_100M_DB800ZL_SSD6_R_DP")
		)
		(pad "B16" smd rect
			(at -2.29997 1.005078 90)
			(size 0.381 1.27)
			(layers "F.Cu" "F.Mask" "F.Paste")
			(net "GND")
		)
		(pad "B17" smd rect
			(at -2.29997 1.605026 90)
			(size 0.381 1.27)
			(layers "F.Cu" "F.Mask" "F.Paste")
			(net "P5E_PEX1_STN2_TX_C_DN<36>")
		)
		(pad "B18" smd rect
			(at -2.29997 2.204974 90)
			(size 0.381 1.27)
			(layers "F.Cu" "F.Mask" "F.Paste")
			(net "P5E_PEX1_STN2_TX_C_DP<36>")
		)
		(pad "B19" smd rect
			(at -2.29997 2.804922 90)
			(size 0.381 1.27)
			(layers "F.Cu" "F.Mask" "F.Paste")
			(net "GND")
		)
		(pad "B20" smd rect
			(at -2.29997 3.405124 90)
			(size 0.381 1.27)
			(layers "F.Cu" "F.Mask" "F.Paste")
			(net "P5E_PEX1_STN2_TX_C_DN<37>")
		)
		(pad "B21" smd rect
			(at -2.29997 4.005072 90)
			(size 0.381 1.27)
			(layers "F.Cu" "F.Mask" "F.Paste")
			(net "P5E_PEX1_STN2_TX_C_DP<37>")
		)
		(pad "B22" smd rect
			(at -2.29997 4.60502 90)
			(size 0.381 1.27)
			(layers "F.Cu" "F.Mask" "F.Paste")
			(net "GND")
		)
		(pad "B23" smd rect
			(at -2.29997 5.204968 90)
			(size 0.381 1.27)
			(layers "F.Cu" "F.Mask" "F.Paste")
			(net "P5E_PEX1_STN2_TX_C_DN<38>")
		)
		(pad "B24" smd rect
			(at -2.29997 5.804916 90)
			(size 0.381 1.27)
			(layers "F.Cu" "F.Mask" "F.Paste")
			(net "P5E_PEX1_STN2_TX_C_DP<38>")
		)
		(pad "B25" smd rect
			(at -2.29997 6.405118 90)
			(size 0.381 1.27)
			(layers "F.Cu" "F.Mask" "F.Paste")
			(net "GND")
		)
		(pad "B26" smd rect
			(at -2.29997 7.005066 90)
			(size 0.381 1.27)
			(layers "F.Cu" "F.Mask" "F.Paste")
			(net "P5E_PEX1_STN2_TX_C_DN<39>")
		)
		(pad "B27" smd rect
			(at -2.29997 7.605014 90)
			(size 0.381 1.27)
			(layers "F.Cu" "F.Mask" "F.Paste")
			(net "P5E_PEX1_STN2_TX_C_DP<39>")
		)
		(pad "B28" smd rect
			(at -2.29997 8.204962 90)
			(size 0.381 1.27)
			(layers "F.Cu" "F.Mask" "F.Paste")
			(net "GND")
		)
		(pad "G1" thru_hole oval
			(at 0 -11.364976 90)
			(size 1.6256 3.4798)
			(drill oval 1.1176 2.4638)
			(layers "*.Cu" "*.Mask")
			(remove_unused_layers no)
			(net "GND")
			(clearance 0.127)
			(thermal_gap 0.127)
		)
		(pad "G2" thru_hole oval
			(at 0 11.364976 90)
			(size 1.6256 3.4798)
			(drill oval 1.1176 2.4638)
			(layers "*.Cu" "*.Mask")
			(remove_unused_layers no)
			(net "GND")
			(clearance 0.127)
			(thermal_gap 0.127)
		)
		(zone
			(layer "F.Cu")
			(hatch none 0.5)
			(connect_pads
				(clearance 0)
			)
			(min_thickness 0.25)
			(keepout
				(tracks not_allowed)
				(vias allowed)
				(pads allowed)
				(copperpour not_allowed)
				(footprints allowed)
			)
			(placement
				(enabled no)
				(sheetname "")
			)
			(fill
				(thermal_gap 0.5)
				(thermal_bridge_width 0.5)
				(island_removal_mode 0)
			)
			(polygon
				(pts
					(xy 182.444898 -38.850062) (xy 179.69484 -38.850062) (xy 179.69484 -35.900106) (xy 182.444898 -35.900106)
				)
			)
		)
		(zone
			(layer "F.Cu")
			(hatch none 0.5)
			(connect_pads
				(clearance 0)
			)
			(min_thickness 0.25)
			(keepout
				(tracks not_allowed)
				(vias allowed)
				(pads allowed)
				(copperpour not_allowed)
				(footprints allowed)
			)
			(placement
				(enabled no)
				(sheetname "")
			)
			(fill
				(thermal_gap 0.5)
				(thermal_bridge_width 0.5)
				(island_removal_mode 0)
			)
			(polygon
				(pts
					(xy 183.515 -17.670018) (xy 179.684934 -17.670018) (xy 179.684934 -14.720062) (xy 183.515 -14.720062)
				)
			)
		)
		(zone
			(layers "F.Cu" "B.Cu" "In1.Cu" "In2.Cu" "In3.Cu" "In4.Cu" "In5.Cu" "In6.Cu"
				"In7.Cu" "In8.Cu" "In9.Cu" "In10.Cu" "In11.Cu" "In12.Cu" "In13.Cu" "In14.Cu"
				"In15.Cu" "In16.Cu"
			)
			(hatch none 0.5)
			(connect_pads
				(clearance 0)
			)
			(min_thickness 0.25)
			(keepout
				(tracks not_allowed)
				(vias allowed)
				(pads allowed)
				(copperpour not_allowed)
				(footprints allowed)
			)
			(placement
				(enabled no)
				(sheetname "")
			)
			(fill
				(thermal_gap 0.5)
				(thermal_bridge_width 0.5)
				(island_removal_mode 0)
			)
			(polygon
				(pts
					(arc
						(start 182.030116 -36.60013)
						(mid 180.099716 -36.60013)
						(end 182.030116 -36.60013)
					)
				)
			)
		)
		(zone
			(layers "F.Cu" "B.Cu" "In1.Cu" "In2.Cu" "In3.Cu" "In4.Cu" "In5.Cu" "In6.Cu"
				"In7.Cu" "In8.Cu" "In9.Cu" "In10.Cu" "In11.Cu" "In12.Cu" "In13.Cu" "In14.Cu"
				"In15.Cu" "In16.Cu"
			)
			(hatch none 0.5)
			(connect_pads
				(clearance 0)
			)
			(min_thickness 0.25)
			(keepout
				(tracks not_allowed)
				(vias allowed)
				(pads allowed)
				(copperpour not_allowed)
				(footprints allowed)
			)
			(placement
				(enabled no)
				(sheetname "")
			)
			(fill
				(thermal_gap 0.5)
				(thermal_bridge_width 0.5)
				(island_removal_mode 0)
			)
			(polygon
				(pts
					(arc
						(start 183.780176 -16.969994)
						(mid 181.849776 -16.969994)
						(end 183.780176 -16.969994)
					)
				)
			)
		)
	)
)
